(kicad_pcb
	(version 20260206)
	(generator "pcbnew")
	(generator_version "10.0")
	(general
		(thickness 1.6)
		(legacy_teardrops no)
	)
	(paper "A4")
	(title_block
		(title "04192023_DAF0TMB3IC0_F0TG_MB_C_brd_V02_OCP.brd")
		(comment 1 "Grand Teton / footprints 3293-3298 of 8354")
	)
	(layers
		(0 "F.Cu" signal "TOP")
		(4 "In1.Cu" signal "GND")
		(6 "In2.Cu" signal "IN1")
		(8 "In3.Cu" signal "GND1")
		(10 "In4.Cu" signal "IN2")
		(12 "In5.Cu" signal "GND2")
		(14 "In6.Cu" signal "IN3")
		(16 "In7.Cu" signal "GND3")
		(18 "In8.Cu" signal "VCC")
		(20 "In9.Cu" signal "VCC1")
		(22 "In10.Cu" signal "GND4")
		(24 "In11.Cu" signal "IN4")
		(26 "In12.Cu" signal "GND5")
		(28 "In13.Cu" signal "IN5")
		(30 "In14.Cu" signal "GND6")
		(32 "In15.Cu" signal "IN6")
		(34 "In16.Cu" signal "GND7")
		(2 "B.Cu" signal "BOTTOM")
		(9 "F.Adhes" user "F.Adhesive")
		(11 "B.Adhes" user "B.Adhesive")
		(13 "F.Paste" user "Package Geometry/Pastemask Top")
		(15 "B.Paste" user "Package Geometry/Pastemask Bottom")
		(5 "F.SilkS" user "Ref Des/Silkscreen Top")
		(7 "B.SilkS" user "Ref Des/Silkscreen Bottom")
		(1 "F.Mask" user "Board Geometry/Soldermask Top")
		(3 "B.Mask" user "Board Geometry/Soldermask Bottom")
		(17 "Dwgs.User" user "User.Drawings")
		(19 "Cmts.User" user "User.Comments")
		(21 "Eco1.User" user "User.Eco1")
		(23 "Eco2.User" user "User.Eco2")
		(25 "Edge.Cuts" user "Board Geometry/Outline")
		(27 "Margin" user)
		(31 "F.CrtYd" user "Package Geometry/Place Bound Top")
		(29 "B.CrtYd" user "Package Geometry/Place Bound Bottom")
		(35 "F.Fab" user "Ref Des/Assembly Top")
		(33 "B.Fab" user "Ref Des/Assembly Bottom")
	)
	(footprint ""
		(layer "F.Cu")
		(at 330.922884 -339.35797)
		(property "Reference" "PC85_1"
			(at 0 0 0)
			(layer "F.SilkS")
			(hide yes)
			(effects
				(font
					(size 1.27 1.27)
				)
			)
		)
		(property "Value" ""
			(at 0 0 0)
			(layer "F.Fab")
			(effects
				(font
					(size 1.27 1.27)
				)
			)
		)
		(duplicate_pad_numbers_are_jumpers no)
		(fp_line
			(start -0.7874 -0.4064)
			(end 0.7874 -0.4064)
			(stroke
				(width 0.1524)
				(type default)
			)
			(layer "F.SilkS")
		)
		(fp_line
			(start -0.7874 0.4064)
			(end -0.7874 -0.4064)
			(stroke
				(width 0.1524)
				(type default)
			)
			(layer "F.SilkS")
		)
		(fp_line
			(start 0.7874 -0.4064)
			(end 0.7874 0.4064)
			(stroke
				(width 0.1524)
				(type default)
			)
			(layer "F.SilkS")
		)
		(fp_line
			(start 0.7874 0.4064)
			(end -0.7874 0.4064)
			(stroke
				(width 0.1524)
				(type default)
			)
			(layer "F.SilkS")
		)
		(fp_line
			(start -0.67945 -0.305054)
			(end -0.12065 -0.305054)
			(stroke
				(width 0.1)
				(type default)
			)
			(layer "F.Fab")
		)
		(fp_line
			(start -0.67945 0.3048)
			(end -0.67945 -0.305054)
			(stroke
				(width 0.1)
				(type default)
			)
			(layer "F.Fab")
		)
		(fp_line
			(start -0.12065 -0.305054)
			(end -0.12065 -0.2794)
			(stroke
				(width 0.1)
				(type default)
			)
			(layer "F.Fab")
		)
		(fp_line
			(start -0.12065 -0.2794)
			(end 0.12065 -0.2794)
			(stroke
				(width 0.1)
				(type default)
			)
			(layer "F.Fab")
		)
		(fp_line
			(start -0.12065 0.2794)
			(end -0.12065 0.3048)
			(stroke
				(width 0.1)
				(type default)
			)
			(layer "F.Fab")
		)
		(fp_line
			(start -0.12065 0.3048)
			(end -0.67945 0.3048)
			(stroke
				(width 0.1)
				(type default)
			)
			(layer "F.Fab")
		)
		(fp_line
			(start 0.120396 0.2794)
			(end -0.12065 0.2794)
			(stroke
				(width 0.1)
				(type default)
			)
			(layer "F.Fab")
		)
		(fp_line
			(start 0.120396 0.3048)
			(end 0.120396 0.2794)
			(stroke
				(width 0.1)
				(type default)
			)
			(layer "F.Fab")
		)
		(fp_line
			(start 0.12065 -0.3048)
			(end 0.67945 -0.3048)
			(stroke
				(width 0.1)
				(type default)
			)
			(layer "F.Fab")
		)
		(fp_line
			(start 0.12065 -0.2794)
			(end 0.12065 -0.3048)
			(stroke
				(width 0.1)
				(type default)
			)
			(layer "F.Fab")
		)
		(fp_line
			(start 0.67945 -0.3048)
			(end 0.67945 0.3048)
			(stroke
				(width 0.1)
				(type default)
			)
			(layer "F.Fab")
		)
		(fp_line
			(start 0.67945 0.3048)
			(end 0.120396 0.3048)
			(stroke
				(width 0.1)
				(type default)
			)
			(layer "F.Fab")
		)
		(pad "1" smd circle
			(at -0.40005 0)
			(size 0 0)
			(layers "F.Cu" "F.Mask" "F.Paste")
			(net "SW_P12V_AUX_PVDDCR_CPU1_P0_FLT")
		)
		(pad "2" smd circle
			(at 0.40005 0)
			(size 0 0)
			(layers "F.Cu" "F.Mask" "F.Paste")
			(net "GND")
		)
	)
	(footprint ""
		(layer "F.Cu")
		(at 221.67088 -42.255948)
		(property "Reference" "C1998"
			(at 0 0 0)
			(layer "F.SilkS")
			(hide yes)
			(effects
				(font
					(size 1.27 1.27)
				)
			)
		)
		(property "Value" ""
			(at 0 0 0)
			(layer "F.Fab")
			(effects
				(font
					(size 1.27 1.27)
				)
			)
		)
		(duplicate_pad_numbers_are_jumpers no)
		(fp_line
			(start -0.7874 -0.4064)
			(end 0.7874 -0.4064)
			(stroke
				(width 0.1524)
				(type default)
			)
			(layer "F.SilkS")
		)
		(fp_line
			(start -0.7874 0.4064)
			(end -0.7874 -0.4064)
			(stroke
				(width 0.1524)
				(type default)
			)
			(layer "F.SilkS")
		)
		(fp_line
			(start 0.7874 -0.4064)
			(end 0.7874 0.4064)
			(stroke
				(width 0.1524)
				(type default)
			)
			(layer "F.SilkS")
		)
		(fp_line
			(start 0.7874 0.4064)
			(end -0.7874 0.4064)
			(stroke
				(width 0.1524)
				(type default)
			)
			(layer "F.SilkS")
		)
		(fp_line
			(start -0.67945 -0.305054)
			(end -0.12065 -0.305054)
			(stroke
				(width 0.1)
				(type default)
			)
			(layer "F.Fab")
		)
		(fp_line
			(start -0.67945 0.3048)
			(end -0.67945 -0.305054)
			(stroke
				(width 0.1)
				(type default)
			)
			(layer "F.Fab")
		)
		(fp_line
			(start -0.12065 -0.305054)
			(end -0.12065 -0.2794)
			(stroke
				(width 0.1)
				(type default)
			)
			(layer "F.Fab")
		)
		(fp_line
			(start -0.12065 -0.2794)
			(end 0.12065 -0.2794)
			(stroke
				(width 0.1)
				(type default)
			)
			(layer "F.Fab")
		)
		(fp_line
			(start -0.12065 0.2794)
			(end -0.12065 0.3048)
			(stroke
				(width 0.1)
				(type default)
			)
			(layer "F.Fab")
		)
		(fp_line
			(start -0.12065 0.3048)
			(end -0.67945 0.3048)
			(stroke
				(width 0.1)
				(type default)
			)
			(layer "F.Fab")
		)
		(fp_line
			(start 0.120396 0.2794)
			(end -0.12065 0.2794)
			(stroke
				(width 0.1)
				(type default)
			)
			(layer "F.Fab")
		)
		(fp_line
			(start 0.120396 0.3048)
			(end 0.120396 0.2794)
			(stroke
				(width 0.1)
				(type default)
			)
			(layer "F.Fab")
		)
		(fp_line
			(start 0.12065 -0.3048)
			(end 0.67945 -0.3048)
			(stroke
				(width 0.1)
				(type default)
			)
			(layer "F.Fab")
		)
		(fp_line
			(start 0.12065 -0.2794)
			(end 0.12065 -0.3048)
			(stroke
				(width 0.1)
				(type default)
			)
			(layer "F.Fab")
		)
		(fp_line
			(start 0.67945 -0.3048)
			(end 0.67945 0.3048)
			(stroke
				(width 0.1)
				(type default)
			)
			(layer "F.Fab")
		)
		(fp_line
			(start 0.67945 0.3048)
			(end 0.120396 0.3048)
			(stroke
				(width 0.1)
				(type default)
			)
			(layer "F.Fab")
		)
		(pad "1" smd circle
			(at -0.40005 0)
			(size 0 0)
			(layers "F.Cu" "F.Mask" "F.Paste")
			(net "P3V3_E1S_0")
		)
		(pad "2" smd circle
			(at 0.40005 0)
			(size 0 0)
			(layers "F.Cu" "F.Mask" "F.Paste")
			(net "GND")
		)
	)
	(footprint ""
		(layer "F.Cu")
		(at 20.480782 -411.707584 180)
		(property "Reference" "PR6804"
			(at 0 0 180)
			(layer "F.SilkS")
			(hide yes)
			(effects
				(font
					(size 1.27 1.27)
				)
			)
		)
		(property "Value" ""
			(at 0 0 180)
			(layer "F.Fab")
			(effects
				(font
					(size 1.27 1.27)
				)
			)
		)
		(duplicate_pad_numbers_are_jumpers no)
		(fp_line
			(start 0.7874 0.4064)
			(end -0.7874 0.4064)
			(stroke
				(width 0.1524)
				(type default)
			)
			(layer "F.SilkS")
		)
		(fp_line
			(start 0.7874 -0.4064)
			(end 0.7874 0.4064)
			(stroke
				(width 0.1524)
				(type default)
			)
			(layer "F.SilkS")
		)
		(fp_line
			(start -0.7874 0.4064)
			(end -0.7874 -0.4064)
			(stroke
				(width 0.1524)
				(type default)
			)
			(layer "F.SilkS")
		)
		(fp_line
			(start -0.7874 -0.4064)
			(end 0.7874 -0.4064)
			(stroke
				(width 0.1524)
				(type default)
			)
			(layer "F.SilkS")
		)
		(fp_line
			(start 0.67945 0.3048)
			(end 0.120396 0.3048)
			(stroke
				(width 0.1)
				(type default)
			)
			(layer "F.Fab")
		)
		(fp_line
			(start 0.67945 -0.3048)
			(end 0.67945 0.3048)
			(stroke
				(width 0.1)
				(type default)
			)
			(layer "F.Fab")
		)
		(fp_line
			(start 0.12065 -0.2794)
			(end 0.12065 -0.3048)
			(stroke
				(width 0.1)
				(type default)
			)
			(layer "F.Fab")
		)
		(fp_line
			(start 0.12065 -0.3048)
			(end 0.67945 -0.3048)
			(stroke
				(width 0.1)
				(type default)
			)
			(layer "F.Fab")
		)
		(fp_line
			(start 0.120396 0.3048)
			(end 0.120396 0.2794)
			(stroke
				(width 0.1)
				(type default)
			)
			(layer "F.Fab")
		)
		(fp_line
			(start 0.120396 0.2794)
			(end -0.12065 0.2794)
			(stroke
				(width 0.1)
				(type default)
			)
			(layer "F.Fab")
		)
		(fp_line
			(start -0.12065 0.3048)
			(end -0.67945 0.3048)
			(stroke
				(width 0.1)
				(type default)
			)
			(layer "F.Fab")
		)
		(fp_line
			(start -0.12065 0.2794)
			(end -0.12065 0.3048)
			(stroke
				(width 0.1)
				(type default)
			)
			(layer "F.Fab")
		)
		(fp_line
			(start -0.12065 -0.2794)
			(end 0.12065 -0.2794)
			(stroke
				(width 0.1)
				(type default)
			)
			(layer "F.Fab")
		)
		(fp_line
			(start -0.12065 -0.305054)
			(end -0.12065 -0.2794)
			(stroke
				(width 0.1)
				(type default)
			)
			(layer "F.Fab")
		)
		(fp_line
			(start -0.67945 0.3048)
			(end -0.67945 -0.305054)
			(stroke
				(width 0.1)
				(type default)
			)
			(layer "F.Fab")
		)
		(fp_line
			(start -0.67945 -0.305054)
			(end -0.12065 -0.305054)
			(stroke
				(width 0.1)
				(type default)
			)
			(layer "F.Fab")
		)
		(pad "1" smd circle
			(at -0.40005 0 180)
			(size 0 0)
			(layers "F.Cu" "F.Mask" "F.Paste")
			(net "P3V3_AUX")
		)
		(pad "2" smd circle
			(at 0.40005 0 180)
			(size 0 0)
			(layers "F.Cu" "F.Mask" "F.Paste")
			(net "P0V9_RETIMER_CPU1_SVID_SDA")
		)
	)
	(footprint ""
		(layer "F.Cu")
		(at 432.085496 -109.13745 90)
		(property "Reference" "PR3780"
			(at 0 0 90)
			(layer "F.SilkS")
			(hide yes)
			(effects
				(font
					(size 1.27 1.27)
				)
			)
		)
		(property "Value" ""
			(at 0 0 90)
			(layer "F.Fab")
			(effects
				(font
					(size 1.27 1.27)
				)
			)
		)
		(duplicate_pad_numbers_are_jumpers no)
		(fp_line
			(start 0.7874 -0.4064)
			(end 0.7874 0.4064)
			(stroke
				(width 0.1524)
				(type default)
			)
			(layer "F.SilkS")
		)
		(fp_line
			(start -0.7874 -0.4064)
			(end 0.7874 -0.4064)
			(stroke
				(width 0.1524)
				(type default)
			)
			(layer "F.SilkS")
		)
		(fp_line
			(start 0.7874 0.4064)
			(end -0.7874 0.4064)
			(stroke
				(width 0.1524)
				(type default)
			)
			(layer "F.SilkS")
		)
		(fp_line
			(start -0.7874 0.4064)
			(end -0.7874 -0.4064)
			(stroke
				(width 0.1524)
				(type default)
			)
			(layer "F.SilkS")
		)
		(fp_line
			(start -0.12065 -0.305054)
			(end -0.12065 -0.2794)
			(stroke
				(width 0.1)
				(type default)
			)
			(layer "F.Fab")
		)
		(fp_line
			(start -0.67945 -0.305054)
			(end -0.12065 -0.305054)
			(stroke
				(width 0.1)
				(type default)
			)
			(layer "F.Fab")
		)
		(fp_line
			(start 0.67945 -0.3048)
			(end 0.67945 0.3048)
			(stroke
				(width 0.1)
				(type default)
			)
			(layer "F.Fab")
		)
		(fp_line
			(start 0.12065 -0.3048)
			(end 0.67945 -0.3048)
			(stroke
				(width 0.1)
				(type default)
			)
			(layer "F.Fab")
		)
		(fp_line
			(start 0.12065 -0.2794)
			(end 0.12065 -0.3048)
			(stroke
				(width 0.1)
				(type default)
			)
			(layer "F.Fab")
		)
		(fp_line
			(start -0.12065 -0.2794)
			(end 0.12065 -0.2794)
			(stroke
				(width 0.1)
				(type default)
			)
			(layer "F.Fab")
		)
		(fp_line
			(start 0.120396 0.2794)
			(end -0.12065 0.2794)
			(stroke
				(width 0.1)
				(type default)
			)
			(layer "F.Fab")
		)
		(fp_line
			(start -0.12065 0.2794)
			(end -0.12065 0.3048)
			(stroke
				(width 0.1)
				(type default)
			)
			(layer "F.Fab")
		)
		(fp_line
			(start 0.67945 0.3048)
			(end 0.120396 0.3048)
			(stroke
				(width 0.1)
				(type default)
			)
			(layer "F.Fab")
		)
		(fp_line
			(start 0.120396 0.3048)
			(end 0.120396 0.2794)
			(stroke
				(width 0.1)
				(type default)
			)
			(layer "F.Fab")
		)
		(fp_line
			(start -0.12065 0.3048)
			(end -0.67945 0.3048)
			(stroke
				(width 0.1)
				(type default)
			)
			(layer "F.Fab")
		)
		(fp_line
			(start -0.67945 0.3048)
			(end -0.67945 -0.305054)
			(stroke
				(width 0.1)
				(type default)
			)
			(layer "F.Fab")
		)
		(pad "1" smd circle
			(at -0.40005 0 90)
			(size 0 0)
			(layers "F.Cu" "F.Mask" "F.Paste")
			(net "P3V3_OCP_CB_1")
		)
		(pad "2" smd circle
			(at 0.40005 0 90)
			(size 0 0)
			(layers "F.Cu" "F.Mask" "F.Paste")
			(net "GND")
		)
	)
	(footprint ""
		(layer "F.Cu")
		(at 20.369784 -393.539726)
		(property "Reference" "PC6613_1"
			(at 0 0 0)
			(layer "F.SilkS")
			(hide yes)
			(effects
				(font
					(size 1.27 1.27)
				)
			)
		)
		(property "Value" ""
			(at 0 0 0)
			(layer "F.Fab")
			(effects
				(font
					(size 1.27 1.27)
				)
			)
		)
		(duplicate_pad_numbers_are_jumpers no)
		(fp_line
			(start -0.7874 -0.4064)
			(end 0.7874 -0.4064)
			(stroke
				(width 0.1524)
				(type default)
			)
			(layer "F.SilkS")
		)
		(fp_line
			(start -0.7874 0.4064)
			(end -0.7874 -0.4064)
			(stroke
				(width 0.1524)
				(type default)
			)
			(layer "F.SilkS")
		)
		(fp_line
			(start 0.7874 -0.4064)
			(end 0.7874 0.4064)
			(stroke
				(width 0.1524)
				(type default)
			)
			(layer "F.SilkS")
		)
		(fp_line
			(start 0.7874 0.4064)
			(end -0.7874 0.4064)
			(stroke
				(width 0.1524)
				(type default)
			)
			(layer "F.SilkS")
		)
		(fp_line
			(start -0.67945 -0.305054)
			(end -0.12065 -0.305054)
			(stroke
				(width 0.1)
				(type default)
			)
			(layer "F.Fab")
		)
		(fp_line
			(start -0.67945 0.3048)
			(end -0.67945 -0.305054)
			(stroke
				(width 0.1)
				(type default)
			)
			(layer "F.Fab")
		)
		(fp_line
			(start -0.12065 -0.305054)
			(end -0.12065 -0.2794)
			(stroke
				(width 0.1)
				(type default)
			)
			(layer "F.Fab")
		)
		(fp_line
			(start -0.12065 -0.2794)
			(end 0.12065 -0.2794)
			(stroke
				(width 0.1)
				(type default)
			)
			(layer "F.Fab")
		)
		(fp_line
			(start -0.12065 0.2794)
			(end -0.12065 0.3048)
			(stroke
				(width 0.1)
				(type default)
			)
			(layer "F.Fab")
		)
		(fp_line
			(start -0.12065 0.3048)
			(end -0.67945 0.3048)
			(stroke
				(width 0.1)
				(type default)
			)
			(layer "F.Fab")
		)
		(fp_line
			(start 0.120396 0.2794)
			(end -0.12065 0.2794)
			(stroke
				(width 0.1)
				(type default)
			)
			(layer "F.Fab")
		)
		(fp_line
			(start 0.120396 0.3048)
			(end 0.120396 0.2794)
			(stroke
				(width 0.1)
				(type default)
			)
			(layer "F.Fab")
		)
		(fp_line
			(start 0.12065 -0.3048)
			(end 0.67945 -0.3048)
			(stroke
				(width 0.1)
				(type default)
			)
			(layer "F.Fab")
		)
		(fp_line
			(start 0.12065 -0.2794)
			(end 0.12065 -0.3048)
			(stroke
				(width 0.1)
				(type default)
			)
			(layer "F.Fab")
		)
		(fp_line
			(start 0.67945 -0.3048)
			(end 0.67945 0.3048)
			(stroke
				(width 0.1)
				(type default)
			)
			(layer "F.Fab")
		)
		(fp_line
			(start 0.67945 0.3048)
			(end 0.120396 0.3048)
			(stroke
				(width 0.1)
				(type default)
			)
			(layer "F.Fab")
		)
		(pad "1" smd circle
			(at -0.40005 0)
			(size 0 0)
			(layers "F.Cu" "F.Mask" "F.Paste")
			(net "SW_P12V_AUX_P0V9_RETIMER_CPU1_FLT")
		)
		(pad "2" smd circle
			(at 0.40005 0)
			(size 0 0)
			(layers "F.Cu" "F.Mask" "F.Paste")
			(net "GND")
		)
	)
	(footprint ""
		(layer "F.Cu")
		(at 200.914 -103.505)
		(property "Reference" "R8082"
			(at 0 0 0)
			(layer "F.SilkS")
			(hide yes)
			(effects
				(font
					(size 1.27 1.27)
				)
			)
		)
		(property "Value" ""
			(at 0 0 0)
			(layer "F.Fab")
			(effects
				(font
					(size 1.27 1.27)
				)
			)
		)
		(duplicate_pad_numbers_are_jumpers no)
		(fp_line
			(start -0.7874 -0.4064)
			(end 0.7874 -0.4064)
			(stroke
				(width 0.1524)
				(type default)
			)
			(layer "F.SilkS")
		)
		(fp_line
			(start -0.7874 0.4064)
			(end -0.7874 -0.4064)
			(stroke
				(width 0.1524)
				(type default)
			)
			(layer "F.SilkS")
		)
		(fp_line
			(start 0.7874 -0.4064)
			(end 0.7874 0.4064)
			(stroke
				(width 0.1524)
				(type default)
			)
			(layer "F.SilkS")
		)
		(fp_line
			(start 0.7874 0.4064)
			(end -0.7874 0.4064)
			(stroke
				(width 0.1524)
				(type default)
			)
			(layer "F.SilkS")
		)
		(fp_line
			(start -0.67945 -0.305054)
			(end -0.12065 -0.305054)
			(stroke
				(width 0.1)
				(type default)
			)
			(layer "F.Fab")
		)
		(fp_line
			(start -0.67945 0.3048)
			(end -0.67945 -0.305054)
			(stroke
				(width 0.1)
				(type default)
			)
			(layer "F.Fab")
		)
		(fp_line
			(start -0.12065 -0.305054)
			(end -0.12065 -0.2794)
			(stroke
				(width 0.1)
				(type default)
			)
			(layer "F.Fab")
		)
		(fp_line
			(start -0.12065 -0.2794)
			(end 0.12065 -0.2794)
			(stroke
				(width 0.1)
				(type default)
			)
			(layer "F.Fab")
		)
		(fp_line
			(start -0.12065 0.2794)
			(end -0.12065 0.3048)
			(stroke
				(width 0.1)
				(type default)
			)
			(layer "F.Fab")
		)
		(fp_line
			(start -0.12065 0.3048)
			(end -0.67945 0.3048)
			(stroke
				(width 0.1)
				(type default)
			)
			(layer "F.Fab")
		)
		(fp_line
			(start 0.120396 0.2794)
			(end -0.12065 0.2794)
			(stroke
				(width 0.1)
				(type default)
			)
			(layer "F.Fab")
		)
		(fp_line
			(start 0.120396 0.3048)
			(end 0.120396 0.2794)
			(stroke
				(width 0.1)
				(type default)
			)
			(layer "F.Fab")
		)
		(fp_line
			(start 0.12065 -0.3048)
			(end 0.67945 -0.3048)
			(stroke
				(width 0.1)
				(type default)
			)
			(layer "F.Fab")
		)
		(fp_line
			(start 0.12065 -0.2794)
			(end 0.12065 -0.3048)
			(stroke
				(width 0.1)
				(type default)
			)
			(layer "F.Fab")
		)
		(fp_line
			(start 0.67945 -0.3048)
			(end 0.67945 0.3048)
			(stroke
				(width 0.1)
				(type default)
			)
			(layer "F.Fab")
		)
		(fp_line
			(start 0.67945 0.3048)
			(end 0.120396 0.3048)
			(stroke
				(width 0.1)
				(type default)
			)
			(layer "F.Fab")
		)
		(pad "1" smd circle
			(at -0.40005 0)
			(size 0 0)
			(layers "F.Cu" "F.Mask" "F.Paste")
			(net "P3V3_AUX")
		)
		(pad "2" smd circle
			(at 0.40005 0)
			(size 0 0)
			(layers "F.Cu" "F.Mask" "F.Paste")
			(net "PWRGD_CHAF_CPU0_R1")
		)
	)
)
